(kicad_pcb
	(version 20260206)
	(generator "pcbnew")
	(generator_version "10.0")
	(general
		(thickness 1.6)
		(legacy_teardrops no)
	)
	(paper "A4")
	(title_block
		(title "04192023_DAF0TMB3IC0_F0TG_MB_C_brd_V02_OCP.brd")
		(comment 1 "Grand Teton / footprints 7365-7370 of 8354")
	)
	(layers
		(0 "F.Cu" signal "TOP")
		(4 "In1.Cu" signal "GND")
		(6 "In2.Cu" signal "IN1")
		(8 "In3.Cu" signal "GND1")
		(10 "In4.Cu" signal "IN2")
		(12 "In5.Cu" signal "GND2")
		(14 "In6.Cu" signal "IN3")
		(16 "In7.Cu" signal "GND3")
		(18 "In8.Cu" signal "VCC")
		(20 "In9.Cu" signal "VCC1")
		(22 "In10.Cu" signal "GND4")
		(24 "In11.Cu" signal "IN4")
		(26 "In12.Cu" signal "GND5")
		(28 "In13.Cu" signal "IN5")
		(30 "In14.Cu" signal "GND6")
		(32 "In15.Cu" signal "IN6")
		(34 "In16.Cu" signal "GND7")
		(2 "B.Cu" signal "BOTTOM")
		(9 "F.Adhes" user "F.Adhesive")
		(11 "B.Adhes" user "B.Adhesive")
		(13 "F.Paste" user "Package Geometry/Pastemask Top")
		(15 "B.Paste" user "Package Geometry/Pastemask Bottom")
		(5 "F.SilkS" user "Ref Des/Silkscreen Top")
		(7 "B.SilkS" user "Ref Des/Silkscreen Bottom")
		(1 "F.Mask" user "Board Geometry/Soldermask Top")
		(3 "B.Mask" user "Board Geometry/Soldermask Bottom")
		(17 "Dwgs.User" user "User.Drawings")
		(19 "Cmts.User" user "User.Comments")
		(21 "Eco1.User" user "User.Eco1")
		(23 "Eco2.User" user "User.Eco2")
		(25 "Edge.Cuts" user "Board Geometry/Outline")
		(27 "Margin" user)
		(31 "F.CrtYd" user "Package Geometry/Place Bound Top")
		(29 "B.CrtYd" user "Package Geometry/Place Bound Bottom")
		(35 "F.Fab" user "Ref Des/Assembly Top")
		(33 "B.Fab" user "Ref Des/Assembly Bottom")
	)
	(footprint ""
		(layer "B.Cu")
		(at 173.609 -98.135948 90)
		(property "Reference" "R6017"
			(at 0 0 90)
			(layer "B.SilkS")
			(hide yes)
			(effects
				(font
					(size 1.27 1.27)
				)
				(justify mirror)
			)
		)
		(property "Value" ""
			(at 0 0 90)
			(layer "B.Fab")
			(effects
				(font
					(size 1.27 1.27)
				)
				(justify mirror)
			)
		)
		(duplicate_pad_numbers_are_jumpers no)
		(fp_line
			(start 0.7874 -0.4064)
			(end -0.7874 -0.4064)
			(stroke
				(width 0.1524)
				(type default)
			)
			(layer "B.SilkS")
		)
		(fp_line
			(start -0.7874 -0.4064)
			(end -0.7874 0.4064)
			(stroke
				(width 0.1524)
				(type default)
			)
			(layer "B.SilkS")
		)
		(fp_line
			(start 0.7874 0.4064)
			(end 0.7874 -0.4064)
			(stroke
				(width 0.1524)
				(type default)
			)
			(layer "B.SilkS")
		)
		(fp_line
			(start -0.7874 0.4064)
			(end 0.7874 0.4064)
			(stroke
				(width 0.1524)
				(type default)
			)
			(layer "B.SilkS")
		)
		(fp_line
			(start 0.67945 -0.305054)
			(end 0.12065 -0.305054)
			(stroke
				(width 0.1)
				(type default)
			)
			(layer "B.Fab")
		)
		(fp_line
			(start 0.12065 -0.305054)
			(end 0.12065 -0.2794)
			(stroke
				(width 0.1)
				(type default)
			)
			(layer "B.Fab")
		)
		(fp_line
			(start -0.12065 -0.3048)
			(end -0.67945 -0.3048)
			(stroke
				(width 0.1)
				(type default)
			)
			(layer "B.Fab")
		)
		(fp_line
			(start -0.67945 -0.3048)
			(end -0.67945 0.3048)
			(stroke
				(width 0.1)
				(type default)
			)
			(layer "B.Fab")
		)
		(fp_line
			(start 0.12065 -0.2794)
			(end -0.12065 -0.2794)
			(stroke
				(width 0.1)
				(type default)
			)
			(layer "B.Fab")
		)
		(fp_line
			(start -0.12065 -0.2794)
			(end -0.12065 -0.3048)
			(stroke
				(width 0.1)
				(type default)
			)
			(layer "B.Fab")
		)
		(fp_line
			(start 0.12065 0.2794)
			(end 0.12065 0.3048)
			(stroke
				(width 0.1)
				(type default)
			)
			(layer "B.Fab")
		)
		(fp_line
			(start -0.120396 0.2794)
			(end 0.12065 0.2794)
			(stroke
				(width 0.1)
				(type default)
			)
			(layer "B.Fab")
		)
		(fp_line
			(start 0.67945 0.3048)
			(end 0.67945 -0.305054)
			(stroke
				(width 0.1)
				(type default)
			)
			(layer "B.Fab")
		)
		(fp_line
			(start 0.12065 0.3048)
			(end 0.67945 0.3048)
			(stroke
				(width 0.1)
				(type default)
			)
			(layer "B.Fab")
		)
		(fp_line
			(start -0.120396 0.3048)
			(end -0.120396 0.2794)
			(stroke
				(width 0.1)
				(type default)
			)
			(layer "B.Fab")
		)
		(fp_line
			(start -0.67945 0.3048)
			(end -0.120396 0.3048)
			(stroke
				(width 0.1)
				(type default)
			)
			(layer "B.Fab")
		)
		(pad "1" smd circle
			(at 0.40005 0 270)
			(size 0 0)
			(layers "B.Cu" "B.Mask" "B.Paste")
			(net "P3V3_AUX")
		)
		(pad "2" smd circle
			(at -0.40005 0 270)
			(size 0 0)
			(layers "B.Cu" "B.Mask" "B.Paste")
			(net "SGPIO_SCM_CLK_<0>")
		)
	)
	(footprint ""
		(layer "B.Cu")
		(at 91.987878 -138.40841 -90)
		(property "Reference" "R175"
			(at 0 0 90)
			(layer "B.SilkS")
			(hide yes)
			(effects
				(font
					(size 1.27 1.27)
				)
				(justify mirror)
			)
		)
		(property "Value" ""
			(at 0 0 90)
			(layer "B.Fab")
			(effects
				(font
					(size 1.27 1.27)
				)
				(justify mirror)
			)
		)
		(duplicate_pad_numbers_are_jumpers no)
		(fp_line
			(start -0.7874 0.4064)
			(end 0.7874 0.4064)
			(stroke
				(width 0.1524)
				(type default)
			)
			(layer "B.SilkS")
		)
		(fp_line
			(start 0.7874 0.4064)
			(end 0.7874 -0.4064)
			(stroke
				(width 0.1524)
				(type default)
			)
			(layer "B.SilkS")
		)
		(fp_line
			(start -0.7874 -0.4064)
			(end -0.7874 0.4064)
			(stroke
				(width 0.1524)
				(type default)
			)
			(layer "B.SilkS")
		)
		(fp_line
			(start 0.7874 -0.4064)
			(end -0.7874 -0.4064)
			(stroke
				(width 0.1524)
				(type default)
			)
			(layer "B.SilkS")
		)
		(fp_line
			(start -0.67945 0.3048)
			(end -0.120396 0.3048)
			(stroke
				(width 0.1)
				(type default)
			)
			(layer "B.Fab")
		)
		(fp_line
			(start -0.120396 0.3048)
			(end -0.120396 0.2794)
			(stroke
				(width 0.1)
				(type default)
			)
			(layer "B.Fab")
		)
		(fp_line
			(start 0.12065 0.3048)
			(end 0.67945 0.3048)
			(stroke
				(width 0.1)
				(type default)
			)
			(layer "B.Fab")
		)
		(fp_line
			(start 0.67945 0.3048)
			(end 0.67945 -0.305054)
			(stroke
				(width 0.1)
				(type default)
			)
			(layer "B.Fab")
		)
		(fp_line
			(start -0.120396 0.2794)
			(end 0.12065 0.2794)
			(stroke
				(width 0.1)
				(type default)
			)
			(layer "B.Fab")
		)
		(fp_line
			(start 0.12065 0.2794)
			(end 0.12065 0.3048)
			(stroke
				(width 0.1)
				(type default)
			)
			(layer "B.Fab")
		)
		(fp_line
			(start -0.12065 -0.2794)
			(end -0.12065 -0.3048)
			(stroke
				(width 0.1)
				(type default)
			)
			(layer "B.Fab")
		)
		(fp_line
			(start 0.12065 -0.2794)
			(end -0.12065 -0.2794)
			(stroke
				(width 0.1)
				(type default)
			)
			(layer "B.Fab")
		)
		(fp_line
			(start -0.67945 -0.3048)
			(end -0.67945 0.3048)
			(stroke
				(width 0.1)
				(type default)
			)
			(layer "B.Fab")
		)
		(fp_line
			(start -0.12065 -0.3048)
			(end -0.67945 -0.3048)
			(stroke
				(width 0.1)
				(type default)
			)
			(layer "B.Fab")
		)
		(fp_line
			(start 0.12065 -0.305054)
			(end 0.12065 -0.2794)
			(stroke
				(width 0.1)
				(type default)
			)
			(layer "B.Fab")
		)
		(fp_line
			(start 0.67945 -0.305054)
			(end 0.12065 -0.305054)
			(stroke
				(width 0.1)
				(type default)
			)
			(layer "B.Fab")
		)
		(pad "1" smd circle
			(at 0.40005 0 90)
			(size 0 0)
			(layers "B.Cu" "B.Mask" "B.Paste")
			(net "SMB_VR_3V3STBY_SCL")
		)
		(pad "2" smd circle
			(at -0.40005 0 90)
			(size 0 0)
			(layers "B.Cu" "B.Mask" "B.Paste")
			(net "PVDDCR_CPU0_P1_PMSCL_R")
		)
	)
	(footprint ""
		(layer "B.Cu")
		(at 453.191118 -244.08511)
		(property "Reference" "R386"
			(at 0 0 0)
			(layer "B.SilkS")
			(hide yes)
			(effects
				(font
					(size 1.27 1.27)
				)
				(justify mirror)
			)
		)
		(property "Value" ""
			(at 0 0 0)
			(layer "B.Fab")
			(effects
				(font
					(size 1.27 1.27)
				)
				(justify mirror)
			)
		)
		(duplicate_pad_numbers_are_jumpers no)
		(fp_line
			(start -0.7874 -0.4064)
			(end -0.7874 0.4064)
			(stroke
				(width 0.1524)
				(type default)
			)
			(layer "B.SilkS")
		)
		(fp_line
			(start -0.7874 0.4064)
			(end 0.7874 0.4064)
			(stroke
				(width 0.1524)
				(type default)
			)
			(layer "B.SilkS")
		)
		(fp_line
			(start 0.7874 -0.4064)
			(end -0.7874 -0.4064)
			(stroke
				(width 0.1524)
				(type default)
			)
			(layer "B.SilkS")
		)
		(fp_line
			(start 0.7874 0.4064)
			(end 0.7874 -0.4064)
			(stroke
				(width 0.1524)
				(type default)
			)
			(layer "B.SilkS")
		)
		(fp_line
			(start -0.67945 -0.3048)
			(end -0.67945 0.3048)
			(stroke
				(width 0.1)
				(type default)
			)
			(layer "B.Fab")
		)
		(fp_line
			(start -0.67945 0.3048)
			(end -0.120396 0.3048)
			(stroke
				(width 0.1)
				(type default)
			)
			(layer "B.Fab")
		)
		(fp_line
			(start -0.12065 -0.3048)
			(end -0.67945 -0.3048)
			(stroke
				(width 0.1)
				(type default)
			)
			(layer "B.Fab")
		)
		(fp_line
			(start -0.12065 -0.2794)
			(end -0.12065 -0.3048)
			(stroke
				(width 0.1)
				(type default)
			)
			(layer "B.Fab")
		)
		(fp_line
			(start -0.120396 0.2794)
			(end 0.12065 0.2794)
			(stroke
				(width 0.1)
				(type default)
			)
			(layer "B.Fab")
		)
		(fp_line
			(start -0.120396 0.3048)
			(end -0.120396 0.2794)
			(stroke
				(width 0.1)
				(type default)
			)
			(layer "B.Fab")
		)
		(fp_line
			(start 0.12065 -0.305054)
			(end 0.12065 -0.2794)
			(stroke
				(width 0.1)
				(type default)
			)
			(layer "B.Fab")
		)
		(fp_line
			(start 0.12065 -0.2794)
			(end -0.12065 -0.2794)
			(stroke
				(width 0.1)
				(type default)
			)
			(layer "B.Fab")
		)
		(fp_line
			(start 0.12065 0.2794)
			(end 0.12065 0.3048)
			(stroke
				(width 0.1)
				(type default)
			)
			(layer "B.Fab")
		)
		(fp_line
			(start 0.12065 0.3048)
			(end 0.67945 0.3048)
			(stroke
				(width 0.1)
				(type default)
			)
			(layer "B.Fab")
		)
		(fp_line
			(start 0.67945 -0.305054)
			(end 0.12065 -0.305054)
			(stroke
				(width 0.1)
				(type default)
			)
			(layer "B.Fab")
		)
		(fp_line
			(start 0.67945 0.3048)
			(end 0.67945 -0.305054)
			(stroke
				(width 0.1)
				(type default)
			)
			(layer "B.Fab")
		)
		(pad "1" smd circle
			(at 0.40005 0 180)
			(size 0 0)
			(layers "B.Cu" "B.Mask" "B.Paste")
			(net "M_L_CPU0_ALERT_N")
		)
		(pad "2" smd circle
			(at -0.40005 0 180)
			(size 0 0)
			(layers "B.Cu" "B.Mask" "B.Paste")
			(net "M_L_CPU0_ALERT_R_N")
		)
	)
	(footprint ""
		(layer "B.Cu")
		(at 349.675958 -272.284952 180)
		(property "Reference" "C2234"
			(at 0 0 0)
			(layer "B.SilkS")
			(hide yes)
			(effects
				(font
					(size 1.27 1.27)
				)
				(justify mirror)
			)
		)
		(property "Value" ""
			(at 0 0 0)
			(layer "B.Fab")
			(effects
				(font
					(size 1.27 1.27)
				)
				(justify mirror)
			)
		)
		(duplicate_pad_numbers_are_jumpers no)
		(fp_line
			(start 0.7874 0.4064)
			(end 0.7874 -0.4064)
			(stroke
				(width 0.1524)
				(type default)
			)
			(layer "B.SilkS")
		)
		(fp_line
			(start 0.7874 -0.4064)
			(end -0.7874 -0.4064)
			(stroke
				(width 0.1524)
				(type default)
			)
			(layer "B.SilkS")
		)
		(fp_line
			(start -0.7874 0.4064)
			(end 0.7874 0.4064)
			(stroke
				(width 0.1524)
				(type default)
			)
			(layer "B.SilkS")
		)
		(fp_line
			(start -0.7874 -0.4064)
			(end -0.7874 0.4064)
			(stroke
				(width 0.1524)
				(type default)
			)
			(layer "B.SilkS")
		)
		(fp_line
			(start 0.67945 0.3048)
			(end 0.67945 -0.305054)
			(stroke
				(width 0.1)
				(type default)
			)
			(layer "B.Fab")
		)
		(fp_line
			(start 0.67945 -0.305054)
			(end 0.12065 -0.305054)
			(stroke
				(width 0.1)
				(type default)
			)
			(layer "B.Fab")
		)
		(fp_line
			(start 0.12065 0.3048)
			(end 0.67945 0.3048)
			(stroke
				(width 0.1)
				(type default)
			)
			(layer "B.Fab")
		)
		(fp_line
			(start 0.12065 0.2794)
			(end 0.12065 0.3048)
			(stroke
				(width 0.1)
				(type default)
			)
			(layer "B.Fab")
		)
		(fp_line
			(start 0.12065 -0.2794)
			(end -0.12065 -0.2794)
			(stroke
				(width 0.1)
				(type default)
			)
			(layer "B.Fab")
		)
		(fp_line
			(start 0.12065 -0.305054)
			(end 0.12065 -0.2794)
			(stroke
				(width 0.1)
				(type default)
			)
			(layer "B.Fab")
		)
		(fp_line
			(start -0.120396 0.3048)
			(end -0.120396 0.2794)
			(stroke
				(width 0.1)
				(type default)
			)
			(layer "B.Fab")
		)
		(fp_line
			(start -0.120396 0.2794)
			(end 0.12065 0.2794)
			(stroke
				(width 0.1)
				(type default)
			)
			(layer "B.Fab")
		)
		(fp_line
			(start -0.12065 -0.2794)
			(end -0.12065 -0.3048)
			(stroke
				(width 0.1)
				(type default)
			)
			(layer "B.Fab")
		)
		(fp_line
			(start -0.12065 -0.3048)
			(end -0.67945 -0.3048)
			(stroke
				(width 0.1)
				(type default)
			)
			(layer "B.Fab")
		)
		(fp_line
			(start -0.67945 0.3048)
			(end -0.120396 0.3048)
			(stroke
				(width 0.1)
				(type default)
			)
			(layer "B.Fab")
		)
		(fp_line
			(start -0.67945 -0.3048)
			(end -0.67945 0.3048)
			(stroke
				(width 0.1)
				(type default)
			)
			(layer "B.Fab")
		)
		(pad "1" smd circle
			(at 0.40005 0)
			(size 0 0)
			(layers "B.Cu" "B.Mask" "B.Paste")
			(net "PVDDCR_CPU1_P0")
		)
		(pad "2" smd circle
			(at -0.40005 0)
			(size 0 0)
			(layers "B.Cu" "B.Mask" "B.Paste")
			(net "GND")
		)
	)
	(footprint ""
		(layer "B.Cu")
		(at 184.681114 -419.861238)
		(property "Reference" "R2796"
			(at 0 0 0)
			(layer "B.SilkS")
			(hide yes)
			(effects
				(font
					(size 1.27 1.27)
				)
				(justify mirror)
			)
		)
		(property "Value" ""
			(at 0 0 0)
			(layer "B.Fab")
			(effects
				(font
					(size 1.27 1.27)
				)
				(justify mirror)
			)
		)
		(duplicate_pad_numbers_are_jumpers no)
		(fp_line
			(start -0.7874 -0.4064)
			(end -0.7874 0.4064)
			(stroke
				(width 0.1524)
				(type default)
			)
			(layer "B.SilkS")
		)
		(fp_line
			(start -0.7874 0.4064)
			(end 0.7874 0.4064)
			(stroke
				(width 0.1524)
				(type default)
			)
			(layer "B.SilkS")
		)
		(fp_line
			(start 0.7874 -0.4064)
			(end -0.7874 -0.4064)
			(stroke
				(width 0.1524)
				(type default)
			)
			(layer "B.SilkS")
		)
		(fp_line
			(start 0.7874 0.4064)
			(end 0.7874 -0.4064)
			(stroke
				(width 0.1524)
				(type default)
			)
			(layer "B.SilkS")
		)
		(fp_line
			(start -0.67945 -0.3048)
			(end -0.67945 0.3048)
			(stroke
				(width 0.1)
				(type default)
			)
			(layer "B.Fab")
		)
		(fp_line
			(start -0.67945 0.3048)
			(end -0.120396 0.3048)
			(stroke
				(width 0.1)
				(type default)
			)
			(layer "B.Fab")
		)
		(fp_line
			(start -0.12065 -0.3048)
			(end -0.67945 -0.3048)
			(stroke
				(width 0.1)
				(type default)
			)
			(layer "B.Fab")
		)
		(fp_line
			(start -0.12065 -0.2794)
			(end -0.12065 -0.3048)
			(stroke
				(width 0.1)
				(type default)
			)
			(layer "B.Fab")
		)
		(fp_line
			(start -0.120396 0.2794)
			(end 0.12065 0.2794)
			(stroke
				(width 0.1)
				(type default)
			)
			(layer "B.Fab")
		)
		(fp_line
			(start -0.120396 0.3048)
			(end -0.120396 0.2794)
			(stroke
				(width 0.1)
				(type default)
			)
			(layer "B.Fab")
		)
		(fp_line
			(start 0.12065 -0.305054)
			(end 0.12065 -0.2794)
			(stroke
				(width 0.1)
				(type default)
			)
			(layer "B.Fab")
		)
		(fp_line
			(start 0.12065 -0.2794)
			(end -0.12065 -0.2794)
			(stroke
				(width 0.1)
				(type default)
			)
			(layer "B.Fab")
		)
		(fp_line
			(start 0.12065 0.2794)
			(end 0.12065 0.3048)
			(stroke
				(width 0.1)
				(type default)
			)
			(layer "B.Fab")
		)
		(fp_line
			(start 0.12065 0.3048)
			(end 0.67945 0.3048)
			(stroke
				(width 0.1)
				(type default)
			)
			(layer "B.Fab")
		)
		(fp_line
			(start 0.67945 -0.305054)
			(end 0.12065 -0.305054)
			(stroke
				(width 0.1)
				(type default)
			)
			(layer "B.Fab")
		)
		(fp_line
			(start 0.67945 0.3048)
			(end 0.67945 -0.305054)
			(stroke
				(width 0.1)
				(type default)
			)
			(layer "B.Fab")
		)
		(pad "1" smd circle
			(at 0.40005 0 180)
			(size 0 0)
			(layers "B.Cu" "B.Mask" "B.Paste")
			(net "FM_PDB_BUF_EN_R1")
		)
		(pad "2" smd circle
			(at -0.40005 0 180)
			(size 0 0)
			(layers "B.Cu" "B.Mask" "B.Paste")
			(net "MB_PDB_SMB9_R_EN")
		)
	)
	(footprint ""
		(layer "B.Cu")
		(at 118.277386 -248.479564 180)
		(property "Reference" "C2337"
			(at 0 0 0)
			(layer "B.SilkS")
			(hide yes)
			(effects
				(font
					(size 1.27 1.27)
				)
				(justify mirror)
			)
		)
		(property "Value" ""
			(at 0 0 0)
			(layer "B.Fab")
			(effects
				(font
					(size 1.27 1.27)
				)
				(justify mirror)
			)
		)
		(duplicate_pad_numbers_are_jumpers no)
		(fp_line
			(start 0.7874 0.4064)
			(end 0.7874 -0.4064)
			(stroke
				(width 0.1524)
				(type default)
			)
			(layer "B.SilkS")
		)
		(fp_line
			(start 0.7874 -0.4064)
			(end -0.7874 -0.4064)
			(stroke
				(width 0.1524)
				(type default)
			)
			(layer "B.SilkS")
		)
		(fp_line
			(start -0.7874 0.4064)
			(end 0.7874 0.4064)
			(stroke
				(width 0.1524)
				(type default)
			)
			(layer "B.SilkS")
		)
		(fp_line
			(start -0.7874 -0.4064)
			(end -0.7874 0.4064)
			(stroke
				(width 0.1524)
				(type default)
			)
			(layer "B.SilkS")
		)
		(fp_line
			(start 0.67945 0.3048)
			(end 0.67945 -0.305054)
			(stroke
				(width 0.1)
				(type default)
			)
			(layer "B.Fab")
		)
		(fp_line
			(start 0.67945 -0.305054)
			(end 0.12065 -0.305054)
			(stroke
				(width 0.1)
				(type default)
			)
			(layer "B.Fab")
		)
		(fp_line
			(start 0.12065 0.3048)
			(end 0.67945 0.3048)
			(stroke
				(width 0.1)
				(type default)
			)
			(layer "B.Fab")
		)
		(fp_line
			(start 0.12065 0.2794)
			(end 0.12065 0.3048)
			(stroke
				(width 0.1)
				(type default)
			)
			(layer "B.Fab")
		)
		(fp_line
			(start 0.12065 -0.2794)
			(end -0.12065 -0.2794)
			(stroke
				(width 0.1)
				(type default)
			)
			(layer "B.Fab")
		)
		(fp_line
			(start 0.12065 -0.305054)
			(end 0.12065 -0.2794)
			(stroke
				(width 0.1)
				(type default)
			)
			(layer "B.Fab")
		)
		(fp_line
			(start -0.120396 0.3048)
			(end -0.120396 0.2794)
			(stroke
				(width 0.1)
				(type default)
			)
			(layer "B.Fab")
		)
		(fp_line
			(start -0.120396 0.2794)
			(end 0.12065 0.2794)
			(stroke
				(width 0.1)
				(type default)
			)
			(layer "B.Fab")
		)
		(fp_line
			(start -0.12065 -0.2794)
			(end -0.12065 -0.3048)
			(stroke
				(width 0.1)
				(type default)
			)
			(layer "B.Fab")
		)
		(fp_line
			(start -0.12065 -0.3048)
			(end -0.67945 -0.3048)
			(stroke
				(width 0.1)
				(type default)
			)
			(layer "B.Fab")
		)
		(fp_line
			(start -0.67945 0.3048)
			(end -0.120396 0.3048)
			(stroke
				(width 0.1)
				(type default)
			)
			(layer "B.Fab")
		)
		(fp_line
			(start -0.67945 -0.3048)
			(end -0.67945 0.3048)
			(stroke
				(width 0.1)
				(type default)
			)
			(layer "B.Fab")
		)
		(pad "1" smd circle
			(at 0.40005 0)
			(size 0 0)
			(layers "B.Cu" "B.Mask" "B.Paste")
			(net "PVDDCR_CPU0_P1")
		)
		(pad "2" smd circle
			(at -0.40005 0)
			(size 0 0)
			(layers "B.Cu" "B.Mask" "B.Paste")
			(net "GND")
		)
	)
)
